# S9S_MB_2U (Grand Teton) — schematic netlist excerpt (pin names and nets, part order shuffled) for the footprints in the layout excerpt that follows; sources: Cadence DE-HDL packaged netlist, KiCad conversion of 03242023_DA0F0TMBIJ0_F0T_Motherboard_J_brd_V01_OCP.brd

PL33  Q_INDUCTOR  130NH/106A IND  pkg SMLF  page 271 : \1\ = SW_PVCCFA_EHV_FIVRA_CPU0_SW1 ; \2\ = PVCCFA_EHV_FIVRA_CPU0
D91  Q_LED  IC  pkg SMLF  page 252 : A = LED_PWRGD_P1V8_PCH_AUX ; C = LED_PWRGD_P1V8_PCH_AUX_D

(kicad_pcb
	(version 20260206)
	(generator "pcbnew")
	(generator_version "10.0")
	(general
		(thickness 1.6)
		(legacy_teardrops no)
	)
	(paper "A4")
	(title_block
		(title "03242023_DA0F0TMBIJ0_F0T_Motherboard_J_brd_V01_OCP.brd")
		(comment 1 "Grand Teton / footprints 2101-2102 of 6105")
	)
	(layers
		(0 "F.Cu" signal "TOP")
		(4 "In1.Cu" signal "GND")
		(6 "In2.Cu" signal "IN1")
		(8 "In3.Cu" signal "GND1")
		(10 "In4.Cu" signal "IN2")
		(12 "In5.Cu" signal "GND2")
		(14 "In6.Cu" signal "IN3")
		(16 "In7.Cu" signal "GND3")
		(18 "In8.Cu" signal "VCC")
		(20 "In9.Cu" signal "VCC1")
		(22 "In10.Cu" signal "GND4")
		(24 "In11.Cu" signal "IN4")
		(26 "In12.Cu" signal "GND5")
		(28 "In13.Cu" signal "IN5")
		(30 "In14.Cu" signal "GND6")
		(32 "In15.Cu" signal "IN6")
		(34 "In16.Cu" signal "GND7")
		(2 "B.Cu" signal "BOTTOM")
		(9 "F.Adhes" user "F.Adhesive")
		(11 "B.Adhes" user "B.Adhesive")
		(13 "F.Paste" user "Package Geometry/Pastemask Top")
		(15 "B.Paste" user "Package Geometry/Pastemask Bottom")
		(5 "F.SilkS" user "Ref Des/Silkscreen Top")
		(7 "B.SilkS" user "Ref Des/Silkscreen Bottom")
		(1 "F.Mask" user "Board Geometry/Soldermask Top")
		(3 "B.Mask" user "Board Geometry/Soldermask Bottom")
		(17 "Dwgs.User" user "User.Drawings")
		(19 "Cmts.User" user "User.Comments")
		(21 "Eco1.User" user "User.Eco1")
		(23 "Eco2.User" user "User.Eco2")
		(25 "Edge.Cuts" user "Board Geometry/Outline")
		(27 "Margin" user)
		(31 "F.CrtYd" user "Package Geometry/Place Bound Top")
		(29 "B.CrtYd" user "Package Geometry/Place Bound Bottom")
		(35 "F.Fab" user "Ref Des/Assembly Top")
		(33 "B.Fab" user "Ref Des/Assembly Bottom")
	)
	(footprint ""
		(layer "F.Cu")
		(at 416.169348 -353.312984 -90)
		(property "Reference" "PL33"
			(at -2.921254 7.125208 0)
			(unlocked yes)
			(layer "F.SilkS")
			(effects
				(font
					(size 0.7874 0.5842)
					(thickness 0.1524)
				)
				(justify left)
			)
		)
		(property "Value" ""
			(at 0 0 270)
			(layer "F.Fab")
			(effects
				(font
					(size 1.27 1.27)
				)
			)
		)
		(duplicate_pad_numbers_are_jumpers no)
		(fp_line
			(start -4.99999 3.750056)
			(end -4.99999 2.2479)
			(stroke
				(width 0.1524)
				(type default)
			)
			(layer "F.SilkS")
		)
		(fp_line
			(start 0 3.750056)
			(end -4.99999 3.750056)
			(stroke
				(width 0.1524)
				(type default)
			)
			(layer "F.SilkS")
		)
		(fp_line
			(start 4.99999 3.750056)
			(end 0 3.750056)
			(stroke
				(width 0.1524)
				(type default)
			)
			(layer "F.SilkS")
		)
		(fp_line
			(start 4.99999 2.2352)
			(end 4.99999 3.750056)
			(stroke
				(width 0.1524)
				(type default)
			)
			(layer "F.SilkS")
		)
		(fp_line
			(start -4.99999 -2.2479)
			(end -4.99999 -3.750056)
			(stroke
				(width 0.1524)
				(type default)
			)
			(layer "F.SilkS")
		)
		(fp_line
			(start -4.99999 -3.750056)
			(end 4.99999 -3.750056)
			(stroke
				(width 0.1524)
				(type default)
			)
			(layer "F.SilkS")
		)
		(fp_line
			(start 4.99999 -3.750056)
			(end 4.99999 -2.2479)
			(stroke
				(width 0.1524)
				(type default)
			)
			(layer "F.SilkS")
		)
		(fp_line
			(start -4.99999 3.750056)
			(end -4.99999 -3.750056)
			(stroke
				(width 0.1)
				(type default)
			)
			(layer "F.Fab")
		)
		(fp_line
			(start 0 3.750056)
			(end -4.99999 3.750056)
			(stroke
				(width 0.1)
				(type default)
			)
			(layer "F.Fab")
		)
		(fp_line
			(start 4.99999 3.750056)
			(end 0 3.750056)
			(stroke
				(width 0.1)
				(type default)
			)
			(layer "F.Fab")
		)
		(fp_line
			(start -4.99999 -3.750056)
			(end 4.99999 -3.750056)
			(stroke
				(width 0.1)
				(type default)
			)
			(layer "F.Fab")
		)
		(fp_line
			(start 4.99999 -3.750056)
			(end 4.99999 3.750056)
			(stroke
				(width 0.1)
				(type default)
			)
			(layer "F.Fab")
		)
		(pad "1" smd rect
			(at -3.299968 0 270)
			(size 3.302 4.2164)
			(layers "F.Cu" "F.Mask" "F.Paste")
			(net "SW_PVCCFA_EHV_FIVRA_CPU0_SW1")
		)
		(pad "2" smd rect
			(at 3.299968 0 270)
			(size 3.302 4.2164)
			(layers "F.Cu" "F.Mask" "F.Paste")
			(net "PVCCFA_EHV_FIVRA_CPU0")
		)
	)
	(footprint ""
		(layer "F.Cu")
		(at 109.599476 -79.078836)
		(property "Reference" "D91"
			(at -54.33441 38.649402 90)
			(unlocked yes)
			(layer "F.SilkS")
			(effects
				(font
					(size 0.635 0.4064)
					(thickness 0.1524)
				)
				(justify left)
			)
		)
		(property "Value" ""
			(at 0 0 0)
			(layer "F.Fab")
			(effects
				(font
					(size 1.27 1.27)
				)
			)
		)
		(duplicate_pad_numbers_are_jumpers no)
		(fp_line
			(start -0.90678 0.4826)
			(end -0.90678 -0.4699)
			(stroke
				(width 0.1524)
				(type default)
			)
			(layer "F.SilkS")
		)
		(fp_line
			(start -0.89408 -0.4826)
			(end 0.90678 -0.4826)
			(stroke
				(width 0.1524)
				(type default)
			)
			(layer "F.SilkS")
		)
		(fp_line
			(start -0.79248 -0.4826)
			(end 1.03378 -0.4826)
			(stroke
				(width 0.1524)
				(type default)
			)
			(layer "F.SilkS")
		)
		(fp_line
			(start -0.64008 -0.4826)
			(end 1.16078 -0.4826)
			(stroke
				(width 0.1524)
				(type default)
			)
			(layer "F.SilkS")
		)
		(fp_line
			(start 0.90678 -0.4826)
			(end 0.90678 0.4826)
			(stroke
				(width 0.1524)
				(type default)
			)
			(layer "F.SilkS")
		)
		(fp_line
			(start 0.90678 0.4826)
			(end -0.90678 0.4826)
			(stroke
				(width 0.1524)
				(type default)
			)
			(layer "F.SilkS")
		)
		(fp_line
			(start 1.03378 -0.4826)
			(end 1.03378 0.4826)
			(stroke
				(width 0.1524)
				(type default)
			)
			(layer "F.SilkS")
		)
		(fp_line
			(start 1.03378 0.4826)
			(end -0.79248 0.4826)
			(stroke
				(width 0.1524)
				(type default)
			)
			(layer "F.SilkS")
		)
		(fp_line
			(start 1.16078 -0.4826)
			(end 1.16078 0.4826)
			(stroke
				(width 0.1524)
				(type default)
			)
			(layer "F.SilkS")
		)
		(fp_line
			(start 1.16078 0.4826)
			(end -0.64008 0.4826)
			(stroke
				(width 0.1524)
				(type default)
			)
			(layer "F.SilkS")
		)
		(fp_line
			(start -0.499872 -0.249936)
			(end 0.499872 -0.249936)
			(stroke
				(width 0.1)
				(type default)
			)
			(layer "F.Fab")
		)
		(fp_line
			(start -0.499872 0.249936)
			(end -0.499872 -0.249936)
			(stroke
				(width 0.1)
				(type default)
			)
			(layer "F.Fab")
		)
		(fp_line
			(start 0.499872 -0.249936)
			(end 0.499872 0.249936)
			(stroke
				(width 0.1)
				(type default)
			)
			(layer "F.Fab")
		)
		(fp_line
			(start 0.499872 0.249936)
			(end -0.499872 0.249936)
			(stroke
				(width 0.1)
				(type default)
			)
			(layer "F.Fab")
		)
		(pad "A" smd rect
			(at -0.47498 0)
			(size 0.6096 0.7112)
			(layers "F.Cu" "F.Mask" "F.Paste")
			(net "LED_PWRGD_P1V8_PCH_AUX")
		)
		(pad "C" smd rect
			(at 0.47498 0)
			(size 0.6096 0.7112)
			(layers "F.Cu" "F.Mask" "F.Paste")
			(net "LED_PWRGD_P1V8_PCH_AUX_D")
		)
	)
)
